(kicad_pcb
	(version 20260206)
	(generator "pcbnew")
	(generator_version "10.0")
	(general
		(thickness 1.6)
		(legacy_teardrops no)
	)
	(paper "A4")
	(title_block
		(title "9054_F0T_PDB_BD_GPU_F_V04_1213_1550_OCP.brd")
		(comment 1 "Grand Teton / footprints 273-276 of 608")
	)
	(layers
		(0 "F.Cu" signal "TOP")
		(4 "In1.Cu" signal "GND")
		(6 "In2.Cu" signal "IN1")
		(8 "In3.Cu" signal "GND1")
		(10 "In4.Cu" signal "VCC")
		(12 "In5.Cu" signal "VCC1")
		(14 "In6.Cu" signal "GND2")
		(16 "In7.Cu" signal "IN2")
		(18 "In8.Cu" signal "GND3")
		(2 "B.Cu" signal "BOTTOM")
		(9 "F.Adhes" user "F.Adhesive")
		(11 "B.Adhes" user "B.Adhesive")
		(13 "F.Paste" user "Package Geometry/Pastemask Top")
		(15 "B.Paste" user "Package Geometry/Pastemask Bottom")
		(5 "F.SilkS" user "Ref Des/Silkscreen Top")
		(7 "B.SilkS" user "Ref Des/Silkscreen Bottom")
		(1 "F.Mask" user "Board Geometry/Soldermask Top")
		(3 "B.Mask" user "Board Geometry/Soldermask Bottom")
		(17 "Dwgs.User" user "User.Drawings")
		(19 "Cmts.User" user "User.Comments")
		(21 "Eco1.User" user "User.Eco1")
		(23 "Eco2.User" user "User.Eco2")
		(25 "Edge.Cuts" user "Board Geometry/Outline")
		(27 "Margin" user)
		(31 "F.CrtYd" user "Package Geometry/Place Bound Top")
		(29 "B.CrtYd" user "Package Geometry/Place Bound Bottom")
		(35 "F.Fab" user "Ref Des/Assembly Top")
		(33 "B.Fab" user "Ref Des/Assembly Bottom")
	)
	(footprint ""
		(layer "F.Cu")
		(at 413.75584 -27.852878 90)
		(property "Reference" "R5925"
			(at 0 0 90)
			(layer "F.SilkS")
			(hide yes)
			(effects
				(font
					(size 1.27 1.27)
				)
			)
		)
		(property "Value" ""
			(at 0 0 90)
			(layer "F.Fab")
			(effects
				(font
					(size 1.27 1.27)
				)
			)
		)
		(duplicate_pad_numbers_are_jumpers no)
		(fp_line
			(start 0.7874 -0.4064)
			(end 0.7874 0.4064)
			(stroke
				(width 0.1524)
				(type default)
			)
			(layer "F.SilkS")
		)
		(fp_line
			(start -0.7874 -0.4064)
			(end 0.7874 -0.4064)
			(stroke
				(width 0.1524)
				(type default)
			)
			(layer "F.SilkS")
		)
		(fp_line
			(start 0.7874 0.4064)
			(end -0.7874 0.4064)
			(stroke
				(width 0.1524)
				(type default)
			)
			(layer "F.SilkS")
		)
		(fp_line
			(start -0.7874 0.4064)
			(end -0.7874 -0.4064)
			(stroke
				(width 0.1524)
				(type default)
			)
			(layer "F.SilkS")
		)
		(fp_line
			(start -0.12065 -0.305054)
			(end -0.12065 -0.2794)
			(stroke
				(width 0.1)
				(type default)
			)
			(layer "F.Fab")
		)
		(fp_line
			(start -0.67945 -0.305054)
			(end -0.12065 -0.305054)
			(stroke
				(width 0.1)
				(type default)
			)
			(layer "F.Fab")
		)
		(fp_line
			(start 0.67945 -0.3048)
			(end 0.67945 0.3048)
			(stroke
				(width 0.1)
				(type default)
			)
			(layer "F.Fab")
		)
		(fp_line
			(start 0.12065 -0.3048)
			(end 0.67945 -0.3048)
			(stroke
				(width 0.1)
				(type default)
			)
			(layer "F.Fab")
		)
		(fp_line
			(start 0.12065 -0.2794)
			(end 0.12065 -0.3048)
			(stroke
				(width 0.1)
				(type default)
			)
			(layer "F.Fab")
		)
		(fp_line
			(start -0.12065 -0.2794)
			(end 0.12065 -0.2794)
			(stroke
				(width 0.1)
				(type default)
			)
			(layer "F.Fab")
		)
		(fp_line
			(start 0.120396 0.2794)
			(end -0.12065 0.2794)
			(stroke
				(width 0.1)
				(type default)
			)
			(layer "F.Fab")
		)
		(fp_line
			(start -0.12065 0.2794)
			(end -0.12065 0.3048)
			(stroke
				(width 0.1)
				(type default)
			)
			(layer "F.Fab")
		)
		(fp_line
			(start 0.67945 0.3048)
			(end 0.120396 0.3048)
			(stroke
				(width 0.1)
				(type default)
			)
			(layer "F.Fab")
		)
		(fp_line
			(start 0.120396 0.3048)
			(end 0.120396 0.2794)
			(stroke
				(width 0.1)
				(type default)
			)
			(layer "F.Fab")
		)
		(fp_line
			(start -0.12065 0.3048)
			(end -0.67945 0.3048)
			(stroke
				(width 0.1)
				(type default)
			)
			(layer "F.Fab")
		)
		(fp_line
			(start -0.67945 0.3048)
			(end -0.67945 -0.305054)
			(stroke
				(width 0.1)
				(type default)
			)
			(layer "F.Fab")
		)
		(pad "1" smd circle
			(at -0.40005 0 90)
			(size 0 0)
			(layers "F.Cu" "F.Mask" "F.Paste")
			(net "GND")
		)
		(pad "2" smd circle
			(at 0.40005 0 90)
			(size 0 0)
			(layers "F.Cu" "F.Mask" "F.Paste")
			(net "P12V_LED_FB")
		)
	)
	(footprint ""
		(layer "F.Cu")
		(at 445.643 -48.514)
		(property "Reference" "U36"
			(at -2.24663 0.3175 90)
			(unlocked yes)
			(layer "F.SilkS")
			(effects
				(font
					(size 0.7874 0.5842)
					(thickness 0.1524)
				)
				(justify left)
			)
		)
		(property "Value" ""
			(at 0 0 0)
			(layer "F.Fab")
			(effects
				(font
					(size 1.27 1.27)
				)
			)
		)
		(duplicate_pad_numbers_are_jumpers no)
		(fp_line
			(start -1.603248 -1.500124)
			(end 1.603248 -1.500124)
			(stroke
				(width 0.1524)
				(type default)
			)
			(layer "F.SilkS")
		)
		(fp_line
			(start -1.603248 1.500124)
			(end -1.603248 -1.500124)
			(stroke
				(width 0.1524)
				(type default)
			)
			(layer "F.SilkS")
		)
		(fp_line
			(start 1.603248 -1.500124)
			(end 1.603248 1.500124)
			(stroke
				(width 0.1524)
				(type default)
			)
			(layer "F.SilkS")
		)
		(fp_line
			(start 1.603248 1.500124)
			(end -1.603248 1.500124)
			(stroke
				(width 0.1524)
				(type default)
			)
			(layer "F.SilkS")
		)
		(fp_line
			(start -1.249934 -1.169924)
			(end -1.249934 -0.729996)
			(stroke
				(width 0.1)
				(type default)
			)
			(layer "F.Fab")
		)
		(fp_line
			(start -1.249934 -0.729996)
			(end -0.6985 -0.729996)
			(stroke
				(width 0.1)
				(type default)
			)
			(layer "F.Fab")
		)
		(fp_line
			(start -1.249934 0.729996)
			(end -1.249934 1.169924)
			(stroke
				(width 0.1)
				(type default)
			)
			(layer "F.Fab")
		)
		(fp_line
			(start -1.249934 1.169924)
			(end -0.700024 1.169924)
			(stroke
				(width 0.1)
				(type default)
			)
			(layer "F.Fab")
		)
		(fp_line
			(start -0.700024 -1.500124)
			(end -0.700024 -1.169924)
			(stroke
				(width 0.1)
				(type default)
			)
			(layer "F.Fab")
		)
		(fp_line
			(start -0.700024 -1.169924)
			(end -1.249934 -1.169924)
			(stroke
				(width 0.1)
				(type default)
			)
			(layer "F.Fab")
		)
		(fp_line
			(start -0.700024 1.169924)
			(end -0.700024 1.500124)
			(stroke
				(width 0.1)
				(type default)
			)
			(layer "F.Fab")
		)
		(fp_line
			(start -0.700024 1.500124)
			(end 0.700024 1.500124)
			(stroke
				(width 0.1)
				(type default)
			)
			(layer "F.Fab")
		)
		(fp_line
			(start -0.6985 -0.729996)
			(end -0.6985 0.729996)
			(stroke
				(width 0.1)
				(type default)
			)
			(layer "F.Fab")
		)
		(fp_line
			(start -0.6985 0.729996)
			(end -1.249934 0.729996)
			(stroke
				(width 0.1)
				(type default)
			)
			(layer "F.Fab")
		)
		(fp_line
			(start 0.700024 -1.500124)
			(end -0.700024 -1.500124)
			(stroke
				(width 0.1)
				(type default)
			)
			(layer "F.Fab")
		)
		(fp_line
			(start 0.700024 -0.219964)
			(end 0.700024 -1.500124)
			(stroke
				(width 0.1)
				(type default)
			)
			(layer "F.Fab")
		)
		(fp_line
			(start 0.700024 0.219964)
			(end 1.249934 0.219964)
			(stroke
				(width 0.1)
				(type default)
			)
			(layer "F.Fab")
		)
		(fp_line
			(start 0.700024 1.500124)
			(end 0.700024 0.219964)
			(stroke
				(width 0.1)
				(type default)
			)
			(layer "F.Fab")
		)
		(fp_line
			(start 1.249934 -0.219964)
			(end 0.700024 -0.219964)
			(stroke
				(width 0.1)
				(type default)
			)
			(layer "F.Fab")
		)
		(fp_line
			(start 1.249934 0.219964)
			(end 1.249934 -0.219964)
			(stroke
				(width 0.1)
				(type default)
			)
			(layer "F.Fab")
		)
		(fp_rect
			(start -0.700024 1.500124)
			(end 0.700024 -1.500124)
			(stroke
				(width 0)
				(type default)
			)
			(fill no)
			(layer "F.Fab")
		)
		(pad "D" smd rect
			(at 0.999998 0 270)
			(size 0.8128 0.9144)
			(layers "F.Cu" "F.Mask" "F.Paste")
			(net "PWRGD_P3V3_HPDB_R_N")
		)
		(pad "G" smd rect
			(at -0.999998 -0.94996 270)
			(size 0.8128 0.9144)
			(layers "F.Cu" "F.Mask" "F.Paste")
			(net "P3V3_HPDB_PG")
		)
		(pad "S" smd rect
			(at -0.999998 0.94996 270)
			(size 0.8128 0.9144)
			(layers "F.Cu" "F.Mask" "F.Paste")
			(net "GND")
		)
	)
	(footprint ""
		(layer "F.Cu")
		(at 435.5338 -22.352 180)
		(property "Reference" "R59"
			(at 0 0 180)
			(layer "F.SilkS")
			(hide yes)
			(effects
				(font
					(size 1.27 1.27)
				)
			)
		)
		(property "Value" ""
			(at 0 0 180)
			(layer "F.Fab")
			(effects
				(font
					(size 1.27 1.27)
				)
			)
		)
		(duplicate_pad_numbers_are_jumpers no)
		(fp_line
			(start 0.7874 0.4064)
			(end -0.7874 0.4064)
			(stroke
				(width 0.1524)
				(type default)
			)
			(layer "F.SilkS")
		)
		(fp_line
			(start 0.7874 -0.4064)
			(end 0.7874 0.4064)
			(stroke
				(width 0.1524)
				(type default)
			)
			(layer "F.SilkS")
		)
		(fp_line
			(start -0.7874 0.4064)
			(end -0.7874 -0.4064)
			(stroke
				(width 0.1524)
				(type default)
			)
			(layer "F.SilkS")
		)
		(fp_line
			(start -0.7874 -0.4064)
			(end 0.7874 -0.4064)
			(stroke
				(width 0.1524)
				(type default)
			)
			(layer "F.SilkS")
		)
		(fp_line
			(start 0.67945 0.3048)
			(end 0.120396 0.3048)
			(stroke
				(width 0.1)
				(type default)
			)
			(layer "F.Fab")
		)
		(fp_line
			(start 0.67945 -0.3048)
			(end 0.67945 0.3048)
			(stroke
				(width 0.1)
				(type default)
			)
			(layer "F.Fab")
		)
		(fp_line
			(start 0.12065 -0.2794)
			(end 0.12065 -0.3048)
			(stroke
				(width 0.1)
				(type default)
			)
			(layer "F.Fab")
		)
		(fp_line
			(start 0.12065 -0.3048)
			(end 0.67945 -0.3048)
			(stroke
				(width 0.1)
				(type default)
			)
			(layer "F.Fab")
		)
		(fp_line
			(start 0.120396 0.3048)
			(end 0.120396 0.2794)
			(stroke
				(width 0.1)
				(type default)
			)
			(layer "F.Fab")
		)
		(fp_line
			(start 0.120396 0.2794)
			(end -0.12065 0.2794)
			(stroke
				(width 0.1)
				(type default)
			)
			(layer "F.Fab")
		)
		(fp_line
			(start -0.12065 0.3048)
			(end -0.67945 0.3048)
			(stroke
				(width 0.1)
				(type default)
			)
			(layer "F.Fab")
		)
		(fp_line
			(start -0.12065 0.2794)
			(end -0.12065 0.3048)
			(stroke
				(width 0.1)
				(type default)
			)
			(layer "F.Fab")
		)
		(fp_line
			(start -0.12065 -0.2794)
			(end 0.12065 -0.2794)
			(stroke
				(width 0.1)
				(type default)
			)
			(layer "F.Fab")
		)
		(fp_line
			(start -0.12065 -0.305054)
			(end -0.12065 -0.2794)
			(stroke
				(width 0.1)
				(type default)
			)
			(layer "F.Fab")
		)
		(fp_line
			(start -0.67945 0.3048)
			(end -0.67945 -0.305054)
			(stroke
				(width 0.1)
				(type default)
			)
			(layer "F.Fab")
		)
		(fp_line
			(start -0.67945 -0.305054)
			(end -0.12065 -0.305054)
			(stroke
				(width 0.1)
				(type default)
			)
			(layer "F.Fab")
		)
		(pad "1" smd circle
			(at -0.40005 0 180)
			(size 0 0)
			(layers "F.Cu" "F.Mask" "F.Paste")
			(net "P3V3_AUX")
		)
		(pad "2" smd circle
			(at 0.40005 0 180)
			(size 0 0)
			(layers "F.Cu" "F.Mask" "F.Paste")
			(net "FRU_ADDR2")
		)
	)
	(footprint ""
		(layer "F.Cu")
		(at 140.79982 -36.1442 180)
		(property "Reference" "PR6990"
			(at 0 0 180)
			(layer "F.SilkS")
			(hide yes)
			(effects
				(font
					(size 1.27 1.27)
				)
			)
		)
		(property "Value" ""
			(at 0 0 180)
			(layer "F.Fab")
			(effects
				(font
					(size 1.27 1.27)
				)
			)
		)
		(duplicate_pad_numbers_are_jumpers no)
		(fp_line
			(start 1.2954 0.5842)
			(end -1.2954 0.5842)
			(stroke
				(width 0.1524)
				(type default)
			)
			(layer "F.SilkS")
		)
		(fp_line
			(start 1.2954 -0.5842)
			(end 1.2954 0.5842)
			(stroke
				(width 0.1524)
				(type default)
			)
			(layer "F.SilkS")
		)
		(fp_line
			(start -1.2954 0.5842)
			(end -1.2954 -0.5842)
			(stroke
				(width 0.1524)
				(type default)
			)
			(layer "F.SilkS")
		)
		(fp_line
			(start -1.2954 -0.5842)
			(end 1.2954 -0.5842)
			(stroke
				(width 0.1524)
				(type default)
			)
			(layer "F.SilkS")
		)
		(fp_line
			(start 1.1938 0.4064)
			(end 0.8636 0.4064)
			(stroke
				(width 0.1)
				(type default)
			)
			(layer "F.Fab")
		)
		(fp_line
			(start 1.1938 -0.406654)
			(end 1.1938 0.4064)
			(stroke
				(width 0.1)
				(type default)
			)
			(layer "F.Fab")
		)
		(fp_line
			(start 0.8636 0.4572)
			(end -0.8636 0.4572)
			(stroke
				(width 0.1)
				(type default)
			)
			(layer "F.Fab")
		)
		(fp_line
			(start 0.8636 0.4064)
			(end 0.8636 0.4572)
			(stroke
				(width 0.1)
				(type default)
			)
			(layer "F.Fab")
		)
		(fp_line
			(start 0.8636 -0.406654)
			(end 1.1938 -0.406654)
			(stroke
				(width 0.1)
				(type default)
			)
			(layer "F.Fab")
		)
		(fp_line
			(start 0.8636 -0.4572)
			(end 0.8636 -0.406654)
			(stroke
				(width 0.1)
				(type default)
			)
			(layer "F.Fab")
		)
		(fp_line
			(start -0.8636 0.4572)
			(end -0.8636 0.4318)
			(stroke
				(width 0.1)
				(type default)
			)
			(layer "F.Fab")
		)
		(fp_line
			(start -0.8636 0.4318)
			(end -0.8636 0.4064)
			(stroke
				(width 0.1)
				(type default)
			)
			(layer "F.Fab")
		)
		(fp_line
			(start -0.8636 0.4064)
			(end -1.1938 0.4064)
			(stroke
				(width 0.1)
				(type default)
			)
			(layer "F.Fab")
		)
		(fp_line
			(start -0.8636 -0.406654)
			(end -0.8636 -0.4572)
			(stroke
				(width 0.1)
				(type default)
			)
			(layer "F.Fab")
		)
		(fp_line
			(start -0.8636 -0.4572)
			(end 0.8636 -0.4572)
			(stroke
				(width 0.1)
				(type default)
			)
			(layer "F.Fab")
		)
		(fp_line
			(start -1.1938 0.4064)
			(end -1.1938 -0.406654)
			(stroke
				(width 0.1)
				(type default)
			)
			(layer "F.Fab")
		)
		(fp_line
			(start -1.1938 -0.406654)
			(end -0.8636 -0.406654)
			(stroke
				(width 0.1)
				(type default)
			)
			(layer "F.Fab")
		)
		(pad "1" smd rect
			(at -0.7366 0 90)
			(size 0.7112 0.8128)
			(layers "F.Cu" "F.Mask" "F.Paste")
			(net "P52V_HS2_1272_S_N")
		)
		(pad "2" smd rect
			(at 0.7366 0 90)
			(size 0.7112 0.8128)
			(layers "F.Cu" "F.Mask" "F.Paste")
			(net "P52V_HS2_SENSE_N_R2")
		)
	)
)
